(kicad_pcb
	(version 20260206)
	(generator "pcbnew")
	(generator_version "10.0")
	(general
		(thickness 1.6)
		(legacy_teardrops no)
	)
	(paper "A4")
	(title_block
		(title "01162023_DA0F0TEBIF0_F0T_Expander_BD_F_brd_V02_OCP.brd")
		(comment 1 "Grand Teton / footprint 6602 of 9728 (PEX1), pads 714-835 of 2397")
	)
	(layers
		(0 "F.Cu" signal "TOP")
		(4 "In1.Cu" signal "GND")
		(6 "In2.Cu" signal "VCC")
		(8 "In3.Cu" signal "VCC1")
		(10 "In4.Cu" signal "GND1")
		(12 "In5.Cu" signal "IN1")
		(14 "In6.Cu" signal "GND2")
		(16 "In7.Cu" signal "IN2")
		(18 "In8.Cu" signal "GND3")
		(20 "In9.Cu" signal "IN3")
		(22 "In10.Cu" signal "GND4")
		(24 "In11.Cu" signal "IN4")
		(26 "In12.Cu" signal "GND5")
		(28 "In13.Cu" signal "IN5")
		(30 "In14.Cu" signal "GND6")
		(32 "In15.Cu" signal "IN6")
		(34 "In16.Cu" signal "GND7")
		(2 "B.Cu" signal "BOTTOM")
		(9 "F.Adhes" user "F.Adhesive")
		(11 "B.Adhes" user "B.Adhesive")
		(13 "F.Paste" user "Package Geometry/Pastemask Top")
		(15 "B.Paste" user "Package Geometry/Pastemask Bottom")
		(5 "F.SilkS" user "Ref Des/Silkscreen Top")
		(7 "B.SilkS" user "Ref Des/Silkscreen Bottom")
		(1 "F.Mask" user "Board Geometry/Soldermask Top")
		(3 "B.Mask" user "Board Geometry/Soldermask Bottom")
		(17 "Dwgs.User" user "User.Drawings")
		(19 "Cmts.User" user "User.Comments")
		(21 "Eco1.User" user "User.Eco1")
		(23 "Eco2.User" user "User.Eco2")
		(25 "Edge.Cuts" user "Board Geometry/Outline")
		(27 "Margin" user)
		(31 "F.CrtYd" user "Package Geometry/Place Bound Top")
		(29 "B.CrtYd" user "Package Geometry/Place Bound Bottom")
		(35 "F.Fab" user "Ref Des/Assembly Top")
		(33 "B.Fab" user "Ref Des/Assembly Bottom")
	)
	(footprint ""
		(layer "F.Cu")
		(at 175.749966 -295.89984)
		(property "Reference" "PEX1"
			(at -3.353562 35.593274 0)
			(unlocked yes)
			(layer "F.SilkS")
			(effects
				(font
					(size 2.032 1.524)
					(thickness 0.1524)
				)
				(justify left)
			)
		)
		(property "Value" ""
			(at 0 0 0)
			(layer "F.Fab")
			(effects
				(font
					(size 1.27 1.27)
				)
			)
		)
		(duplicate_pad_numbers_are_jumpers no)
		(pad "AP30" smd circle
			(at 4.750054 8.549894)
			(size 0.4572 0.4572)
			(layers "F.Cu" "F.Mask" "F.Paste")
			(net "P1V25_SERDES_VDDPLL_PEX1")
		)
		(pad "AP31" smd circle
			(at 5.700014 8.549894)
			(size 0.4572 0.4572)
			(layers "F.Cu" "F.Mask" "F.Paste")
			(net "P1V25_SERDES_VDDPLL_PEX1")
		)
		(pad "AP32" smd circle
			(at 6.649974 8.549894)
			(size 0.4572 0.4572)
			(layers "F.Cu" "F.Mask" "F.Paste")
			(net "P1V25_SERDES_VDDPLL_PEX1")
		)
		(pad "AP33" smd circle
			(at 7.599934 8.549894)
			(size 0.4572 0.4572)
			(layers "F.Cu" "F.Mask" "F.Paste")
			(net "P1V25_SERDES_VDDPLL_PEX1")
		)
		(pad "AP34" smd circle
			(at 8.549894 8.549894)
			(size 0.4572 0.4572)
			(layers "F.Cu" "F.Mask" "F.Paste")
			(net "GND")
		)
		(pad "AP35" smd circle
			(at 9.500108 8.549894)
			(size 0.4572 0.4572)
			(layers "F.Cu" "F.Mask" "F.Paste")
			(net "P1V8_VDDA_PEX1")
		)
		(pad "AP36" smd circle
			(at 10.450068 8.549894)
			(size 0.4572 0.4572)
			(layers "F.Cu" "F.Mask" "F.Paste")
			(net "Net_498")
		)
		(pad "AP37" smd circle
			(at 11.400028 8.549894)
			(size 0.4572 0.4572)
			(layers "F.Cu" "F.Mask" "F.Paste")
			(net "GND")
		)
		(pad "AP38" smd circle
			(at 12.349988 8.549894)
			(size 0.4572 0.4572)
			(layers "F.Cu" "F.Mask" "F.Paste")
			(net "Net_5290")
		)
		(pad "AP39" smd circle
			(at 13.299948 8.549894)
			(size 0.4572 0.4572)
			(layers "F.Cu" "F.Mask" "F.Paste")
			(net "Net_5296")
		)
		(pad "AP40" smd circle
			(at 14.249908 8.549894)
			(size 0.4572 0.4572)
			(layers "F.Cu" "F.Mask" "F.Paste")
			(net "GND")
		)
		(pad "AP41" smd circle
			(at 15.200122 8.549894)
			(size 0.4572 0.4572)
			(layers "F.Cu" "F.Mask" "F.Paste")
			(net "P5E_PEX1_STN0_TX_DP<1>")
		)
		(pad "AP42" smd circle
			(at 16.150082 8.549894)
			(size 0.4572 0.4572)
			(layers "F.Cu" "F.Mask" "F.Paste")
			(net "P5E_PEX1_STN0_TX_DN<1>")
		)
		(pad "AP43" smd circle
			(at 17.100042 8.549894)
			(size 0.4572 0.4572)
			(layers "F.Cu" "F.Mask" "F.Paste")
			(net "GND")
		)
		(pad "AP44" smd circle
			(at 18.050002 8.549894)
			(size 0.4572 0.4572)
			(layers "F.Cu" "F.Mask" "F.Paste")
			(net "GND")
		)
		(pad "AP45" smd circle
			(at 18.999962 8.549894)
			(size 0.4572 0.4572)
			(layers "F.Cu" "F.Mask" "F.Paste")
			(net "GND")
		)
		(pad "AP46" smd circle
			(at 19.949922 8.549894)
			(size 0.4572 0.4572)
			(layers "F.Cu" "F.Mask" "F.Paste")
			(net "GND")
		)
		(pad "AP47" smd circle
			(at 20.899882 8.549894)
			(size 0.4572 0.4572)
			(layers "F.Cu" "F.Mask" "F.Paste")
			(net "GND")
		)
		(pad "AP48" smd circle
			(at 21.850096 8.549894)
			(size 0.4572 0.4572)
			(layers "F.Cu" "F.Mask" "F.Paste")
			(net "P5E_PEX1_STN0_RX_DP<1>")
		)
		(pad "AP49" smd circle
			(at 22.800056 8.549894)
			(size 0.4572 0.4572)
			(layers "F.Cu" "F.Mask" "F.Paste")
			(net "P5E_PEX1_STN0_RX_DN<1>")
		)
		(pad "AR1" smd circle
			(at -22.800056 9.500108)
			(size 0.4572 0.4572)
			(layers "F.Cu" "F.Mask" "F.Paste")
			(net "GND")
		)
		(pad "AR2" smd circle
			(at -21.850096 9.500108)
			(size 0.4572 0.4572)
			(layers "F.Cu" "F.Mask" "F.Paste")
			(net "GND")
		)
		(pad "AR3" smd circle
			(at -20.899882 9.500108)
			(size 0.4572 0.4572)
			(layers "F.Cu" "F.Mask" "F.Paste")
			(net "Net_1709")
		)
		(pad "AR4" smd circle
			(at -19.949922 9.500108)
			(size 0.4572 0.4572)
			(layers "F.Cu" "F.Mask" "F.Paste")
			(net "Net_1712")
		)
		(pad "AR5" smd circle
			(at -18.999962 9.500108)
			(size 0.4572 0.4572)
			(layers "F.Cu" "F.Mask" "F.Paste")
			(net "GND")
		)
		(pad "AR6" smd circle
			(at -18.050002 9.500108)
			(size 0.4572 0.4572)
			(layers "F.Cu" "F.Mask" "F.Paste")
			(net "Net_1649")
		)
		(pad "AR7" smd circle
			(at -17.100042 9.500108)
			(size 0.4572 0.4572)
			(layers "F.Cu" "F.Mask" "F.Paste")
			(net "Net_1674")
		)
		(pad "AR8" smd circle
			(at -16.150082 9.500108)
			(size 0.4572 0.4572)
			(layers "F.Cu" "F.Mask" "F.Paste")
			(net "GND")
		)
		(pad "AR9" smd circle
			(at -15.200122 9.500108)
			(size 0.4572 0.4572)
			(layers "F.Cu" "F.Mask" "F.Paste")
			(net "GND")
		)
		(pad "AR10" smd circle
			(at -14.249908 9.500108)
			(size 0.4572 0.4572)
			(layers "F.Cu" "F.Mask" "F.Paste")
			(net "GND")
		)
		(pad "AR11" smd circle
			(at -13.299948 9.500108)
			(size 0.4572 0.4572)
			(layers "F.Cu" "F.Mask" "F.Paste")
			(net "GND")
		)
		(pad "AR12" smd circle
			(at -12.349988 9.500108)
			(size 0.4572 0.4572)
			(layers "F.Cu" "F.Mask" "F.Paste")
			(net "GND")
		)
		(pad "AR13" smd circle
			(at -11.400028 9.500108)
			(size 0.4572 0.4572)
			(layers "F.Cu" "F.Mask" "F.Paste")
			(net "GND")
		)
		(pad "AR14" smd circle
			(at -10.450068 9.500108)
			(size 0.4572 0.4572)
			(layers "F.Cu" "F.Mask" "F.Paste")
			(net "GND")
		)
		(pad "AR15" smd circle
			(at -9.500108 9.500108)
			(size 0.4572 0.4572)
			(layers "F.Cu" "F.Mask" "F.Paste")
			(net "GND")
		)
		(pad "AR16" smd circle
			(at -8.549894 9.500108)
			(size 0.4572 0.4572)
			(layers "F.Cu" "F.Mask" "F.Paste")
			(net "GND")
		)
		(pad "AR17" smd circle
			(at -7.599934 9.500108)
			(size 0.4572 0.4572)
			(layers "F.Cu" "F.Mask" "F.Paste")
			(net "GND")
		)
		(pad "AR18" smd circle
			(at -6.649974 9.500108)
			(size 0.4572 0.4572)
			(layers "F.Cu" "F.Mask" "F.Paste")
			(net "GND")
		)
		(pad "AR19" smd circle
			(at -5.700014 9.500108)
			(size 0.4572 0.4572)
			(layers "F.Cu" "F.Mask" "F.Paste")
			(net "GND")
		)
		(pad "AR20" smd circle
			(at -4.750054 9.500108)
			(size 0.4572 0.4572)
			(layers "F.Cu" "F.Mask" "F.Paste")
			(net "GND")
		)
		(pad "AR21" smd circle
			(at -3.800094 9.500108)
			(size 0.4572 0.4572)
			(layers "F.Cu" "F.Mask" "F.Paste")
			(net "GND")
		)
		(pad "AR22" smd circle
			(at -2.84988 9.500108)
			(size 0.4572 0.4572)
			(layers "F.Cu" "F.Mask" "F.Paste")
			(net "GND")
		)
		(pad "AR23" smd circle
			(at -1.89992 9.500108)
			(size 0.4572 0.4572)
			(layers "F.Cu" "F.Mask" "F.Paste")
			(net "GND")
		)
		(pad "AR24" smd circle
			(at -0.94996 9.500108)
			(size 0.4572 0.4572)
			(layers "F.Cu" "F.Mask" "F.Paste")
			(net "GND")
		)
		(pad "AR25" smd circle
			(at 0 9.500108)
			(size 0.4572 0.4572)
			(layers "F.Cu" "F.Mask" "F.Paste")
			(net "GND")
		)
		(pad "AR26" smd circle
			(at 0.94996 9.500108)
			(size 0.4572 0.4572)
			(layers "F.Cu" "F.Mask" "F.Paste")
			(net "GND")
		)
		(pad "AR27" smd circle
			(at 1.89992 9.500108)
			(size 0.4572 0.4572)
			(layers "F.Cu" "F.Mask" "F.Paste")
			(net "GND")
		)
		(pad "AR28" smd circle
			(at 2.84988 9.500108)
			(size 0.4572 0.4572)
			(layers "F.Cu" "F.Mask" "F.Paste")
			(net "GND")
		)
		(pad "AR29" smd circle
			(at 3.800094 9.500108)
			(size 0.4572 0.4572)
			(layers "F.Cu" "F.Mask" "F.Paste")
			(net "GND")
		)
		(pad "AR30" smd circle
			(at 4.750054 9.500108)
			(size 0.4572 0.4572)
			(layers "F.Cu" "F.Mask" "F.Paste")
			(net "GND")
		)
		(pad "AR31" smd circle
			(at 5.700014 9.500108)
			(size 0.4572 0.4572)
			(layers "F.Cu" "F.Mask" "F.Paste")
			(net "GND")
		)
		(pad "AR32" smd circle
			(at 6.649974 9.500108)
			(size 0.4572 0.4572)
			(layers "F.Cu" "F.Mask" "F.Paste")
			(net "GND")
		)
		(pad "AR33" smd circle
			(at 7.599934 9.500108)
			(size 0.4572 0.4572)
			(layers "F.Cu" "F.Mask" "F.Paste")
			(net "GND")
		)
		(pad "AR34" smd circle
			(at 8.549894 9.500108)
			(size 0.4572 0.4572)
			(layers "F.Cu" "F.Mask" "F.Paste")
			(net "GND")
		)
		(pad "AR35" smd circle
			(at 9.500108 9.500108)
			(size 0.4572 0.4572)
			(layers "F.Cu" "F.Mask" "F.Paste")
			(net "GND")
		)
		(pad "AR36" smd circle
			(at 10.450068 9.500108)
			(size 0.4572 0.4572)
			(layers "F.Cu" "F.Mask" "F.Paste")
			(net "Net_500")
		)
		(pad "AR37" smd circle
			(at 11.400028 9.500108)
			(size 0.4572 0.4572)
			(layers "F.Cu" "F.Mask" "F.Paste")
			(net "GND")
		)
		(pad "AR38" smd circle
			(at 12.349988 9.500108)
			(size 0.4572 0.4572)
			(layers "F.Cu" "F.Mask" "F.Paste")
			(net "Net_5295")
		)
		(pad "AR39" smd circle
			(at 13.299948 9.500108)
			(size 0.4572 0.4572)
			(layers "F.Cu" "F.Mask" "F.Paste")
			(net "Net_5297")
		)
		(pad "AR40" smd circle
			(at 14.249908 9.500108)
			(size 0.4572 0.4572)
			(layers "F.Cu" "F.Mask" "F.Paste")
			(net "GND")
		)
		(pad "AR41" smd circle
			(at 15.200122 9.500108)
			(size 0.4572 0.4572)
			(layers "F.Cu" "F.Mask" "F.Paste")
			(net "GND")
		)
		(pad "AR42" smd circle
			(at 16.150082 9.500108)
			(size 0.4572 0.4572)
			(layers "F.Cu" "F.Mask" "F.Paste")
			(net "GND")
		)
		(pad "AR43" smd circle
			(at 17.100042 9.500108)
			(size 0.4572 0.4572)
			(layers "F.Cu" "F.Mask" "F.Paste")
			(net "P5E_PEX1_STN0_TX_DP<2>")
		)
		(pad "AR44" smd circle
			(at 18.050002 9.500108)
			(size 0.4572 0.4572)
			(layers "F.Cu" "F.Mask" "F.Paste")
			(net "P5E_PEX1_STN0_TX_DN<2>")
		)
		(pad "AR45" smd circle
			(at 18.999962 9.500108)
			(size 0.4572 0.4572)
			(layers "F.Cu" "F.Mask" "F.Paste")
			(net "GND")
		)
		(pad "AR46" smd circle
			(at 19.949922 9.500108)
			(size 0.4572 0.4572)
			(layers "F.Cu" "F.Mask" "F.Paste")
			(net "P5E_PEX1_STN0_RX_DP<2>")
		)
		(pad "AR47" smd circle
			(at 20.899882 9.500108)
			(size 0.4572 0.4572)
			(layers "F.Cu" "F.Mask" "F.Paste")
			(net "P5E_PEX1_STN0_RX_DN<2>")
		)
		(pad "AR48" smd circle
			(at 21.850096 9.500108)
			(size 0.4572 0.4572)
			(layers "F.Cu" "F.Mask" "F.Paste")
			(net "GND")
		)
		(pad "AR49" smd circle
			(at 22.800056 9.500108)
			(size 0.4572 0.4572)
			(layers "F.Cu" "F.Mask" "F.Paste")
			(net "GND")
		)
		(pad "AT1" smd circle
			(at -22.800056 10.450068)
			(size 0.4572 0.4572)
			(layers "F.Cu" "F.Mask" "F.Paste")
			(net "Net_1422")
		)
		(pad "AT2" smd circle
			(at -21.850096 10.450068)
			(size 0.4572 0.4572)
			(layers "F.Cu" "F.Mask" "F.Paste")
			(net "Net_1711")
		)
		(pad "AT3" smd circle
			(at -20.899882 10.450068)
			(size 0.4572 0.4572)
			(layers "F.Cu" "F.Mask" "F.Paste")
			(net "GND")
		)
		(pad "AT4" smd circle
			(at -19.949922 10.450068)
			(size 0.4572 0.4572)
			(layers "F.Cu" "F.Mask" "F.Paste")
			(net "GND")
		)
		(pad "AT5" smd circle
			(at -18.999962 10.450068)
			(size 0.4572 0.4572)
			(layers "F.Cu" "F.Mask" "F.Paste")
			(net "GND")
		)
		(pad "AT6" smd circle
			(at -18.050002 10.450068)
			(size 0.4572 0.4572)
			(layers "F.Cu" "F.Mask" "F.Paste")
			(net "GND")
		)
		(pad "AT7" smd circle
			(at -17.100042 10.450068)
			(size 0.4572 0.4572)
			(layers "F.Cu" "F.Mask" "F.Paste")
			(net "GND")
		)
		(pad "AT8" smd circle
			(at -16.150082 10.450068)
			(size 0.4572 0.4572)
			(layers "F.Cu" "F.Mask" "F.Paste")
			(net "Net_1660")
		)
		(pad "AT9" smd circle
			(at -15.200122 10.450068)
			(size 0.4572 0.4572)
			(layers "F.Cu" "F.Mask" "F.Paste")
			(net "Net_1655")
		)
		(pad "AT10" smd circle
			(at -14.249908 10.450068)
			(size 0.4572 0.4572)
			(layers "F.Cu" "F.Mask" "F.Paste")
			(net "GND")
		)
		(pad "AT11" smd circle
			(at -13.299948 10.450068)
			(size 0.4572 0.4572)
			(layers "F.Cu" "F.Mask" "F.Paste")
			(net "GND")
		)
		(pad "AT12" smd circle
			(at -12.349988 10.450068)
			(size 0.4572 0.4572)
			(layers "F.Cu" "F.Mask" "F.Paste")
			(net "GND")
		)
		(pad "AT13" smd circle
			(at -11.400028 10.450068)
			(size 0.4572 0.4572)
			(layers "F.Cu" "F.Mask" "F.Paste")
			(net "GND")
		)
		(pad "AT14" smd circle
			(at -10.450068 10.450068)
			(size 0.4572 0.4572)
			(layers "F.Cu" "F.Mask" "F.Paste")
			(net "GND")
		)
		(pad "AT15" smd circle
			(at -9.500108 10.450068)
			(size 0.4572 0.4572)
			(layers "F.Cu" "F.Mask" "F.Paste")
			(net "GND")
		)
		(pad "AT16" smd circle
			(at -8.549894 10.450068)
			(size 0.4572 0.4572)
			(layers "F.Cu" "F.Mask" "F.Paste")
			(net "GND")
		)
		(pad "AT17" smd circle
			(at -7.599934 10.450068)
			(size 0.4572 0.4572)
			(layers "F.Cu" "F.Mask" "F.Paste")
			(net "GND")
		)
		(pad "AT18" smd circle
			(at -6.649974 10.450068)
			(size 0.4572 0.4572)
			(layers "F.Cu" "F.Mask" "F.Paste")
			(net "GND")
		)
		(pad "AT19" smd circle
			(at -5.700014 10.450068)
			(size 0.4572 0.4572)
			(layers "F.Cu" "F.Mask" "F.Paste")
			(net "GND")
		)
		(pad "AT20" smd circle
			(at -4.750054 10.450068)
			(size 0.4572 0.4572)
			(layers "F.Cu" "F.Mask" "F.Paste")
			(net "GND")
		)
		(pad "AT21" smd circle
			(at -3.800094 10.450068)
			(size 0.4572 0.4572)
			(layers "F.Cu" "F.Mask" "F.Paste")
			(net "GND")
		)
		(pad "AT22" smd circle
			(at -2.84988 10.450068)
			(size 0.4572 0.4572)
			(layers "F.Cu" "F.Mask" "F.Paste")
			(net "GND")
		)
		(pad "AT23" smd circle
			(at -1.89992 10.450068)
			(size 0.4572 0.4572)
			(layers "F.Cu" "F.Mask" "F.Paste")
			(net "GND")
		)
		(pad "AT24" smd circle
			(at -0.94996 10.450068)
			(size 0.4572 0.4572)
			(layers "F.Cu" "F.Mask" "F.Paste")
			(net "GND")
		)
		(pad "AT25" smd circle
			(at 0 10.450068)
			(size 0.4572 0.4572)
			(layers "F.Cu" "F.Mask" "F.Paste")
			(net "GND")
		)
		(pad "AT26" smd circle
			(at 0.94996 10.450068)
			(size 0.4572 0.4572)
			(layers "F.Cu" "F.Mask" "F.Paste")
			(net "GND")
		)
		(pad "AT27" smd circle
			(at 1.89992 10.450068)
			(size 0.4572 0.4572)
			(layers "F.Cu" "F.Mask" "F.Paste")
			(net "GND")
		)
		(pad "AT28" smd circle
			(at 2.84988 10.450068)
			(size 0.4572 0.4572)
			(layers "F.Cu" "F.Mask" "F.Paste")
			(net "GND")
		)
		(pad "AT29" smd circle
			(at 3.800094 10.450068)
			(size 0.4572 0.4572)
			(layers "F.Cu" "F.Mask" "F.Paste")
			(net "GND")
		)
		(pad "AT30" smd circle
			(at 4.750054 10.450068)
			(size 0.4572 0.4572)
			(layers "F.Cu" "F.Mask" "F.Paste")
			(net "GND")
		)
		(pad "AT31" smd circle
			(at 5.700014 10.450068)
			(size 0.4572 0.4572)
			(layers "F.Cu" "F.Mask" "F.Paste")
			(net "GND")
		)
		(pad "AT32" smd circle
			(at 6.649974 10.450068)
			(size 0.4572 0.4572)
			(layers "F.Cu" "F.Mask" "F.Paste")
			(net "GND")
		)
		(pad "AT33" smd circle
			(at 7.599934 10.450068)
			(size 0.4572 0.4572)
			(layers "F.Cu" "F.Mask" "F.Paste")
			(net "GND")
		)
		(pad "AT34" smd circle
			(at 8.549894 10.450068)
			(size 0.4572 0.4572)
			(layers "F.Cu" "F.Mask" "F.Paste")
			(net "GND")
		)
		(pad "AT35" smd circle
			(at 9.500108 10.450068)
			(size 0.4572 0.4572)
			(layers "F.Cu" "F.Mask" "F.Paste")
			(net "GND")
		)
		(pad "AT36" smd circle
			(at 10.450068 10.450068)
			(size 0.4572 0.4572)
			(layers "F.Cu" "F.Mask" "F.Paste")
			(net "Net_503")
		)
		(pad "AT37" smd circle
			(at 11.400028 10.450068)
			(size 0.4572 0.4572)
			(layers "F.Cu" "F.Mask" "F.Paste")
			(net "GND")
		)
		(pad "AT38" smd circle
			(at 12.349988 10.450068)
			(size 0.4572 0.4572)
			(layers "F.Cu" "F.Mask" "F.Paste")
			(net "Net_5261")
		)
		(pad "AT39" smd circle
			(at 13.299948 10.450068)
			(size 0.4572 0.4572)
			(layers "F.Cu" "F.Mask" "F.Paste")
			(net "Net_5246")
		)
		(pad "AT40" smd circle
			(at 14.249908 10.450068)
			(size 0.4572 0.4572)
			(layers "F.Cu" "F.Mask" "F.Paste")
			(net "GND")
		)
		(pad "AT41" smd circle
			(at 15.200122 10.450068)
			(size 0.4572 0.4572)
			(layers "F.Cu" "F.Mask" "F.Paste")
			(net "P5E_PEX1_STN0_TX_DP<3>")
		)
		(pad "AT42" smd circle
			(at 16.150082 10.450068)
			(size 0.4572 0.4572)
			(layers "F.Cu" "F.Mask" "F.Paste")
			(net "P5E_PEX1_STN0_TX_DN<3>")
		)
		(pad "AT43" smd circle
			(at 17.100042 10.450068)
			(size 0.4572 0.4572)
			(layers "F.Cu" "F.Mask" "F.Paste")
			(net "GND")
		)
		(pad "AT44" smd circle
			(at 18.050002 10.450068)
			(size 0.4572 0.4572)
			(layers "F.Cu" "F.Mask" "F.Paste")
			(net "GND")
		)
		(pad "AT45" smd circle
			(at 18.999962 10.450068)
			(size 0.4572 0.4572)
			(layers "F.Cu" "F.Mask" "F.Paste")
			(net "GND")
		)
		(pad "AT46" smd circle
			(at 19.949922 10.450068)
			(size 0.4572 0.4572)
			(layers "F.Cu" "F.Mask" "F.Paste")
			(net "GND")
		)
		(pad "AT47" smd circle
			(at 20.899882 10.450068)
			(size 0.4572 0.4572)
			(layers "F.Cu" "F.Mask" "F.Paste")
			(net "GND")
		)
		(pad "AT48" smd circle
			(at 21.850096 10.450068)
			(size 0.4572 0.4572)
			(layers "F.Cu" "F.Mask" "F.Paste")
			(net "P5E_PEX1_STN0_RX_DP<3>")
		)
		(pad "AT49" smd circle
			(at 22.800056 10.450068)
			(size 0.4572 0.4572)
			(layers "F.Cu" "F.Mask" "F.Paste")
			(net "P5E_PEX1_STN0_RX_DN<3>")
		)
		(pad "AU1" smd circle
			(at -22.800056 11.400028)
			(size 0.4572 0.4572)
			(layers "F.Cu" "F.Mask" "F.Paste")
			(net "GND")
		)
		(pad "AU2" smd circle
			(at -21.850096 11.400028)
			(size 0.4572 0.4572)
			(layers "F.Cu" "F.Mask" "F.Paste")
			(net "GND")
		)
		(pad "AU3" smd circle
			(at -20.899882 11.400028)
			(size 0.4572 0.4572)
			(layers "F.Cu" "F.Mask" "F.Paste")
			(net "Net_1734")
		)
		(pad "AU4" smd circle
			(at -19.949922 11.400028)
			(size 0.4572 0.4572)
			(layers "F.Cu" "F.Mask" "F.Paste")
			(net "Net_1737")
		)
	)
)
